(kicad_pcb
	(version 20260206)
	(generator "pcbnew")
	(generator_version "10.0")
	(general
		(thickness 1.6)
		(legacy_teardrops no)
	)
	(paper "A4")
	(title_block
		(title "12092022_DA0F0TFB6D0_F0T_FAN_BOARD_MP5048_D_brd_v02_OCP.brd")
		(comment 1 "Grand Teton / footprints 427-427 of 924")
	)
	(layers
		(0 "F.Cu" signal "TOP")
		(4 "In1.Cu" signal "GND")
		(6 "In2.Cu" signal "IN1")
		(8 "In3.Cu" signal "IN2")
		(10 "In4.Cu" signal "GND1")
		(2 "B.Cu" signal "BOTTOM")
		(9 "F.Adhes" user "F.Adhesive")
		(11 "B.Adhes" user "B.Adhesive")
		(13 "F.Paste" user "Package Geometry/Pastemask Top")
		(15 "B.Paste" user "Package Geometry/Pastemask Bottom")
		(5 "F.SilkS" user "Ref Des/Silkscreen Top")
		(7 "B.SilkS" user "Ref Des/Silkscreen Bottom")
		(1 "F.Mask" user "Board Geometry/Soldermask Top")
		(3 "B.Mask" user "Board Geometry/Soldermask Bottom")
		(17 "Dwgs.User" user "User.Drawings")
		(19 "Cmts.User" user "User.Comments")
		(21 "Eco1.User" user "User.Eco1")
		(23 "Eco2.User" user "User.Eco2")
		(25 "Edge.Cuts" user "Board Geometry/Outline")
		(27 "Margin" user)
		(31 "F.CrtYd" user "Package Geometry/Place Bound Top")
		(29 "B.CrtYd" user "Package Geometry/Place Bound Bottom")
		(35 "F.Fab" user "Ref Des/Assembly Top")
		(33 "B.Fab" user "Ref Des/Assembly Bottom")
	)
	(footprint ""
		(layer "F.Cu")
		(at 37.338 -207.038956 180)
		(property "Reference" "R5200"
			(at 0 0 180)
			(layer "F.SilkS")
			(hide yes)
			(effects
				(font
					(size 1.27 1.27)
				)
			)
		)
		(property "Value" ""
			(at 0 0 180)
			(layer "F.Fab")
			(effects
				(font
					(size 1.27 1.27)
				)
			)
		)
		(duplicate_pad_numbers_are_jumpers no)
		(fp_line
			(start 0.7874 0.4064)
			(end -0.7874 0.4064)
			(stroke
				(width 0.1524)
				(type default)
			)
			(layer "F.SilkS")
		)
		(fp_line
			(start 0.7874 -0.4064)
			(end 0.7874 0.4064)
			(stroke
				(width 0.1524)
				(type default)
			)
			(layer "F.SilkS")
		)
		(fp_line
			(start -0.7874 0.4064)
			(end -0.7874 -0.4064)
			(stroke
				(width 0.1524)
				(type default)
			)
			(layer "F.SilkS")
		)
		(fp_line
			(start -0.7874 -0.4064)
			(end 0.7874 -0.4064)
			(stroke
				(width 0.1524)
				(type default)
			)
			(layer "F.SilkS")
		)
		(fp_line
			(start 0.67945 0.3048)
			(end 0.120396 0.3048)
			(stroke
				(width 0.1)
				(type default)
			)
			(layer "F.Fab")
		)
		(fp_line
			(start 0.67945 -0.3048)
			(end 0.67945 0.3048)
			(stroke
				(width 0.1)
				(type default)
			)
			(layer "F.Fab")
		)
		(fp_line
			(start 0.12065 -0.2794)
			(end 0.12065 -0.3048)
			(stroke
				(width 0.1)
				(type default)
			)
			(layer "F.Fab")
		)
		(fp_line
			(start 0.12065 -0.3048)
			(end 0.67945 -0.3048)
			(stroke
				(width 0.1)
				(type default)
			)
			(layer "F.Fab")
		)
		(fp_line
			(start 0.120396 0.3048)
			(end 0.120396 0.2794)
			(stroke
				(width 0.1)
				(type default)
			)
			(layer "F.Fab")
		)
		(fp_line
			(start 0.120396 0.2794)
			(end -0.12065 0.2794)
			(stroke
				(width 0.1)
				(type default)
			)
			(layer "F.Fab")
		)
		(fp_line
			(start -0.12065 0.3048)
			(end -0.67945 0.3048)
			(stroke
				(width 0.1)
				(type default)
			)
			(layer "F.Fab")
		)
		(fp_line
			(start -0.12065 0.2794)
			(end -0.12065 0.3048)
			(stroke
				(width 0.1)
				(type default)
			)
			(layer "F.Fab")
		)
		(fp_line
			(start -0.12065 -0.2794)
			(end 0.12065 -0.2794)
			(stroke
				(width 0.1)
				(type default)
			)
			(layer "F.Fab")
		)
		(fp_line
			(start -0.12065 -0.305054)
			(end -0.12065 -0.2794)
			(stroke
				(width 0.1)
				(type default)
			)
			(layer "F.Fab")
		)
		(fp_line
			(start -0.67945 0.3048)
			(end -0.67945 -0.305054)
			(stroke
				(width 0.1)
				(type default)
			)
			(layer "F.Fab")
		)
		(fp_line
			(start -0.67945 -0.305054)
			(end -0.12065 -0.305054)
			(stroke
				(width 0.1)
				(type default)
			)
			(layer "F.Fab")
		)
		(pad "1" smd circle
			(at -0.40005 0 180)
			(size 0 0)
			(layers "F.Cu" "F.Mask" "F.Paste")
			(net "FAN_1_PWM_IL_R")
		)
		(pad "2" smd circle
			(at 0.40005 0 180)
			(size 0 0)
			(layers "F.Cu" "F.Mask" "F.Paste")
			(net "FAN_1_PWM_IL")
		)
	)
)
